# S9S_MB_2U (Grand Teton) — schematic netlist excerpt (pin names and nets, part order shuffled) for the footprints in the layout excerpt that follows; sources: Cadence DE-HDL packaged netlist, KiCad conversion of 03242023_DA0F0TMBIJ0_F0T_Motherboard_J_brd_V01_OCP.brd

C881  Q_CAP_DIFFBUS  DIFF BUS_0.22UF 6.3V 20% X6S  pkg C0201  page 174 : \1\ = P5E_CPU0_PE3_TX_C_DP<10> ; \2\ = P5E_CPU0_PE3_TX_DP<10>
J123  CONN1_10165288101LF  CONN1_10165288-101LF IO  pkg CON_GUIDE-F1XG  page 311 : NC1 = NC

(kicad_pcb
	(version 20260206)
	(generator "pcbnew")
	(generator_version "10.0")
	(general
		(thickness 1.6)
		(legacy_teardrops no)
	)
	(paper "A4")
	(title_block
		(title "03242023_DA0F0TMBIJ0_F0T_Motherboard_J_brd_V01_OCP.brd")
		(comment 1 "Grand Teton / footprints 957-958 of 6105")
	)
	(layers
		(0 "F.Cu" signal "TOP")
		(4 "In1.Cu" signal "GND")
		(6 "In2.Cu" signal "IN1")
		(8 "In3.Cu" signal "GND1")
		(10 "In4.Cu" signal "IN2")
		(12 "In5.Cu" signal "GND2")
		(14 "In6.Cu" signal "IN3")
		(16 "In7.Cu" signal "GND3")
		(18 "In8.Cu" signal "VCC")
		(20 "In9.Cu" signal "VCC1")
		(22 "In10.Cu" signal "GND4")
		(24 "In11.Cu" signal "IN4")
		(26 "In12.Cu" signal "GND5")
		(28 "In13.Cu" signal "IN5")
		(30 "In14.Cu" signal "GND6")
		(32 "In15.Cu" signal "IN6")
		(34 "In16.Cu" signal "GND7")
		(2 "B.Cu" signal "BOTTOM")
		(9 "F.Adhes" user "F.Adhesive")
		(11 "B.Adhes" user "B.Adhesive")
		(13 "F.Paste" user "Package Geometry/Pastemask Top")
		(15 "B.Paste" user "Package Geometry/Pastemask Bottom")
		(5 "F.SilkS" user "Ref Des/Silkscreen Top")
		(7 "B.SilkS" user "Ref Des/Silkscreen Bottom")
		(1 "F.Mask" user "Board Geometry/Soldermask Top")
		(3 "B.Mask" user "Board Geometry/Soldermask Bottom")
		(17 "Dwgs.User" user "User.Drawings")
		(19 "Cmts.User" user "User.Comments")
		(21 "Eco1.User" user "User.Eco1")
		(23 "Eco2.User" user "User.Eco2")
		(25 "Edge.Cuts" user "Board Geometry/Outline")
		(27 "Margin" user)
		(31 "F.CrtYd" user "Package Geometry/Place Bound Top")
		(29 "B.CrtYd" user "Package Geometry/Place Bound Bottom")
		(35 "F.Fab" user "Ref Des/Assembly Top")
		(33 "B.Fab" user "Ref Des/Assembly Bottom")
	)
	(footprint ""
		(layer "F.Cu")
		(at 359.774998 -431.359818 180)
		(property "Reference" "J123"
			(at -0.529082 -11.63828 0)
			(unlocked yes)
			(layer "F.SilkS")
			(effects
				(font
					(size 0.7874 0.5842)
					(thickness 0.1524)
				)
				(justify left)
			)
		)
		(property "Value" ""
			(at 0 0 180)
			(layer "F.Fab")
			(effects
				(font
					(size 1.27 1.27)
				)
			)
		)
		(duplicate_pad_numbers_are_jumpers no)
		(fp_line
			(start 3.525012 21.310092)
			(end 3.525012 -10.489946)
			(stroke
				(width 0.1524)
				(type default)
			)
			(layer "F.SilkS")
		)
		(fp_line
			(start 3.525012 -10.489946)
			(end -3.525012 -10.489946)
			(stroke
				(width 0.1524)
				(type default)
			)
			(layer "F.SilkS")
		)
		(fp_line
			(start -3.525012 21.310092)
			(end 3.525012 21.310092)
			(stroke
				(width 0.1524)
				(type default)
			)
			(layer "F.SilkS")
		)
		(fp_line
			(start -3.525012 10.6299)
			(end 3.525012 10.6299)
			(stroke
				(width 0.1524)
				(type default)
			)
			(layer "F.SilkS")
		)
		(fp_line
			(start -3.525012 -10.489946)
			(end -3.525012 21.310092)
			(stroke
				(width 0.1524)
				(type default)
			)
			(layer "F.SilkS")
		)
		(fp_line
			(start 3.525012 21.310092)
			(end 3.525012 -10.489946)
			(stroke
				(width 0.1)
				(type default)
			)
			(layer "F.Fab")
		)
		(fp_line
			(start 3.525012 -10.489946)
			(end -3.525012 -10.489946)
			(stroke
				(width 0.1)
				(type default)
			)
			(layer "F.Fab")
		)
		(fp_line
			(start -3.525012 21.310092)
			(end 3.525012 21.310092)
			(stroke
				(width 0.1)
				(type default)
			)
			(layer "F.Fab")
		)
		(fp_line
			(start -3.525012 -10.489946)
			(end -3.525012 21.310092)
			(stroke
				(width 0.1)
				(type default)
			)
			(layer "F.Fab")
		)
		(pad "" np_thru_hole circle
			(at 0 -6.620002 180)
			(size 3.175 3.175)
			(drill 3.175)
			(layers "*.Cu" "*.Mask")
			(clearance 0.381)
			(thermal_gap 0.381)
		)
		(pad "" np_thru_hole circle
			(at 0 0 180)
			(size 0 0)
			(drill 3.175)
			(layers "*.Cu" "*.Mask")
			(clearance 0)
		)
		(pad "" np_thru_hole circle
			(at 0 5.130038 180)
			(size 3.175 3.175)
			(drill 3.175)
			(layers "*.Cu" "*.Mask")
			(clearance 0.381)
			(thermal_gap 0.381)
		)
		(zone
			(layers "F.Cu" "B.Cu" "In1.Cu" "In2.Cu" "In3.Cu" "In4.Cu" "In5.Cu" "In6.Cu"
				"In7.Cu" "In8.Cu" "In9.Cu" "In10.Cu" "In11.Cu" "In12.Cu" "In13.Cu" "In14.Cu"
				"In15.Cu" "In16.Cu"
			)
			(hatch none 0.5)
			(connect_pads
				(clearance 0)
			)
			(min_thickness 0.25)
			(keepout
				(tracks not_allowed)
				(vias allowed)
				(pads allowed)
				(copperpour not_allowed)
				(footprints allowed)
			)
			(placement
				(enabled no)
				(sheetname "")
			)
			(fill
				(thermal_gap 0.5)
				(thermal_bridge_width 0.5)
				(island_removal_mode 0)
			)
			(polygon
				(pts
					(arc
						(start 361.870498 -436.489856)
						(mid 357.679498 -436.489856)
						(end 361.870498 -436.489856)
					)
				)
			)
		)
		(zone
			(layers "F.Cu" "B.Cu" "In1.Cu" "In2.Cu" "In3.Cu" "In4.Cu" "In5.Cu" "In6.Cu"
				"In7.Cu" "In8.Cu" "In9.Cu" "In10.Cu" "In11.Cu" "In12.Cu" "In13.Cu" "In14.Cu"
				"In15.Cu" "In16.Cu"
			)
			(hatch none 0.5)
			(connect_pads
				(clearance 0)
			)
			(min_thickness 0.25)
			(keepout
				(tracks not_allowed)
				(vias allowed)
				(pads allowed)
				(copperpour not_allowed)
				(footprints allowed)
			)
			(placement
				(enabled no)
				(sheetname "")
			)
			(fill
				(thermal_gap 0.5)
				(thermal_bridge_width 0.5)
				(island_removal_mode 0)
			)
			(polygon
				(pts
					(arc
						(start 361.870498 -424.739816)
						(mid 357.679498 -424.739816)
						(end 361.870498 -424.739816)
					)
				)
			)
		)
		(zone
			(layers "F.Cu" "B.Cu" "In1.Cu" "In2.Cu" "In3.Cu" "In4.Cu" "In5.Cu" "In6.Cu"
				"In7.Cu" "In8.Cu" "In9.Cu" "In10.Cu" "In11.Cu" "In12.Cu" "In13.Cu" "In14.Cu"
				"In15.Cu" "In16.Cu"
			)
			(hatch none 0.5)
			(connect_pads
				(clearance 0)
			)
			(min_thickness 0.25)
			(keepout
				(tracks not_allowed)
				(vias allowed)
				(pads allowed)
				(copperpour not_allowed)
				(footprints allowed)
			)
			(placement
				(enabled no)
				(sheetname "")
			)
			(fill
				(thermal_gap 0.5)
				(thermal_bridge_width 0.5)
				(island_removal_mode 0)
			)
			(polygon
				(pts
					(arc
						(start 363.394498 -431.359818)
						(mid 356.155498 -431.359818)
						(end 363.394498 -431.359818)
					)
				)
			)
		)
	)
	(footprint ""
		(layer "F.Cu")
		(at 388.97433 -408.517344 -90)
		(property "Reference" "C881"
			(at 0 0 270)
			(layer "F.SilkS")
			(hide yes)
			(effects
				(font
					(size 1.27 1.27)
				)
			)
		)
		(property "Value" ""
			(at 0 0 270)
			(layer "F.Fab")
			(effects
				(font
					(size 1.27 1.27)
				)
			)
		)
		(duplicate_pad_numbers_are_jumpers no)
		(fp_line
			(start -0.299974 0.150114)
			(end -0.299974 -0.150114)
			(stroke
				(width 0.1)
				(type default)
			)
			(layer "F.Fab")
		)
		(fp_line
			(start 0.299974 0.150114)
			(end -0.299974 0.150114)
			(stroke
				(width 0.1)
				(type default)
			)
			(layer "F.Fab")
		)
		(fp_line
			(start -0.299974 -0.150114)
			(end 0.299974 -0.150114)
			(stroke
				(width 0.1)
				(type default)
			)
			(layer "F.Fab")
		)
		(fp_line
			(start 0.299974 -0.150114)
			(end 0.299974 0.150114)
			(stroke
				(width 0.1)
				(type default)
			)
			(layer "F.Fab")
		)
		(pad "1" smd rect
			(at -0.2667 0 270)
			(size 0.3048 0.381)
			(layers "F.Cu" "F.Mask" "F.Paste")
			(net "P5E_CPU0_PE3_TX_C_DP<10>")
		)
		(pad "2" smd rect
			(at 0.2667 0 270)
			(size 0.3048 0.381)
			(layers "F.Cu" "F.Mask" "F.Paste")
			(net "P5E_CPU0_PE3_TX_DP<10>")
		)
	)
)
